G04 ================== begin FILE IDENTIFICATION RECORD ==================*
G04 Layout Name:  17301-sa.brd*
G04 Film Name:    DP_REF_L3*
G04 File Format:  Gerber RS274X*
G04 File Origin:  Cadence Allegro 16.6-2015-S079*
G04 Origin Date:  Thu Jun 22 17:50:10 2017*
G04 *
G04 Layer:  BOARD GEOMETRY/PANEL_OUTLINE*
G04 Layer:  BOARD GEOMETRY/DP_REF_L3_TBL*
G04 Layer:  BOARD GEOMETRY/DP_REF_L3_L3*
G04 *
G04 Offset:    (0.00 0.00)*
G04 Mirror:    No*
G04 Mode:      Positive*
G04 Rotation:  0*
G04 FullContactRelief:  No*
G04 UndefLineWidth:     6.00*
G04 ================== end FILE IDENTIFICATION RECORD ====================*
%FSLAX35Y35*MOIN*%
%IR0*IPPOS*OFA0.00000B0.00000*MIA0B0*SFA1.00000B1.00000*%
%ADD10C,.02*%
%ADD11C,.006*%
%ADD12C,.0056*%
G75*
%LPD*%
G75*
G54D10*
G01X615261Y627846D02*
X1402761D01*
G01X615261Y697146D02*
Y627846D01*
G01Y662496D02*
X1402761D01*
G01X615261Y697146D02*
X1402761D01*
G01X790261D02*
Y627846D01*
G01X1087761Y697146D02*
Y627846D01*
G01X1192761Y697146D02*
Y627846D01*
G01X1402761Y697146D02*
Y627846D01*
G54D11*
G01X-19340Y-32800D02*
Y-50300D01*
G01X-24362Y-32800D02*
X-14318D01*
G01X-5552Y-50300D02*
Y-32800D01*
G01Y-41258D02*
X-4460Y-39800D01*
X-3368Y-38925D01*
X-1622Y-38634D01*
X-312Y-38925D01*
X1217Y-40092D01*
X1872Y-41842D01*
Y-50300D01*
G01X15660Y-38634D02*
Y-50300D01*
G01Y-33967D02*
X15223Y-33675D01*
Y-33092D01*
X15660Y-32800D01*
X16097Y-33092D01*
Y-33675D01*
X15660Y-33967D01*
G01X29885Y-48259D02*
X30977Y-49425D01*
X32505Y-50300D01*
X33815D01*
X35125Y-49717D01*
X35998Y-48842D01*
X36435Y-47676D01*
X36217Y-45925D01*
X35343Y-45050D01*
X31413Y-43300D01*
X30540Y-41258D01*
X30977Y-39800D01*
X31850Y-38925D01*
X33160Y-38634D01*
X34470Y-38925D01*
X35780Y-39800D01*
G01X65103Y-54675D02*
X66632Y-55842D01*
X68378Y-56133D01*
X69906Y-55842D01*
X71217Y-54384D01*
X72090Y-52342D01*
Y-38634D01*
G01Y-40967D02*
X71217Y-39800D01*
X69906Y-38925D01*
X68378Y-38634D01*
X66632Y-39217D01*
X65540Y-40383D01*
X64666Y-42425D01*
X64230Y-44467D01*
X64448Y-46217D01*
X65322Y-48259D01*
X66632Y-49717D01*
X68378Y-50300D01*
X69688Y-50008D01*
X71217Y-48842D01*
X72090Y-47676D01*
G01X82385Y-42425D02*
X89372D01*
X88717Y-40383D01*
X87625Y-39217D01*
X86097Y-38634D01*
X84568Y-38925D01*
X83258Y-39800D01*
X82385Y-41842D01*
X81948Y-43592D01*
Y-45342D01*
X82385Y-47092D01*
X83477Y-48842D01*
X84787Y-50008D01*
X86315Y-50300D01*
X87843Y-49717D01*
X89372Y-47967D01*
G01X100103Y-50300D02*
Y-38634D01*
G01Y-40967D02*
X101195Y-39800D01*
X102287Y-38925D01*
X103815Y-38634D01*
X104906Y-38925D01*
X106217Y-39800D01*
G01X116730Y-50300D02*
Y-32800D01*
G01Y-41550D02*
X117822Y-39800D01*
X119132Y-38925D01*
X120442Y-38634D01*
X122406Y-39217D01*
X123717Y-40383D01*
X124590Y-42425D01*
Y-44758D01*
X124153Y-47092D01*
X123280Y-48842D01*
X121752Y-50008D01*
X120442Y-50300D01*
X119132Y-50008D01*
X117822Y-49134D01*
X116730Y-47676D01*
G01X134885Y-42425D02*
X141872D01*
X141217Y-40383D01*
X140125Y-39217D01*
X138597Y-38634D01*
X137068Y-38925D01*
X135758Y-39800D01*
X134885Y-41842D01*
X134448Y-43592D01*
Y-45342D01*
X134885Y-47092D01*
X135977Y-48842D01*
X137287Y-50008D01*
X138815Y-50300D01*
X140343Y-49717D01*
X141872Y-47967D01*
G01X152603Y-50300D02*
Y-38634D01*
G01Y-40967D02*
X153695Y-39800D01*
X154787Y-38925D01*
X156315Y-38634D01*
X157406Y-38925D01*
X158717Y-39800D01*
G01X190660Y-38634D02*
Y-50300D01*
G01Y-33967D02*
X190223Y-33675D01*
Y-33092D01*
X190660Y-32800D01*
X191097Y-33092D01*
Y-33675D01*
X190660Y-33967D01*
G01X204885Y-48259D02*
X205977Y-49425D01*
X207505Y-50300D01*
X208815D01*
X210125Y-49717D01*
X210998Y-48842D01*
X211435Y-47676D01*
X211217Y-45925D01*
X210343Y-45050D01*
X206413Y-43300D01*
X205540Y-41258D01*
X205977Y-39800D01*
X206850Y-38925D01*
X208160Y-38634D01*
X209470Y-38925D01*
X210780Y-39800D01*
G01X239666Y-54675D02*
X241195Y-55842D01*
X242505Y-56133D01*
X244252Y-55550D01*
X245562Y-54092D01*
X246217Y-51466D01*
Y-38634D01*
G01Y-33967D02*
X245780Y-33675D01*
Y-33092D01*
X246217Y-32800D01*
X246653Y-33092D01*
Y-33675D01*
X246217Y-33967D01*
G01X256948Y-38634D02*
Y-46800D01*
X257822Y-48842D01*
X259132Y-50008D01*
X260660Y-50300D01*
X262188Y-50008D01*
X263498Y-48842D01*
X264372Y-46800D01*
G01Y-50300D02*
Y-38634D01*
G01X274885Y-48259D02*
X275977Y-49425D01*
X277505Y-50300D01*
X278815D01*
X280125Y-49717D01*
X280998Y-48842D01*
X281435Y-47676D01*
X281217Y-45925D01*
X280343Y-45050D01*
X276413Y-43300D01*
X275540Y-41258D01*
X275977Y-39800D01*
X276850Y-38925D01*
X278160Y-38634D01*
X279470Y-38925D01*
X280780Y-39800D01*
G01X295660Y-32800D02*
Y-50300D01*
G01X292603Y-38634D02*
X298717D01*
G01X329350Y-50300D02*
Y-35425D01*
X329787Y-33967D01*
X330660Y-33092D01*
X331970Y-32800D01*
X333280Y-33383D01*
X333935Y-34842D01*
G01X331315Y-39800D02*
X326948D01*
G01X348160Y-50300D02*
X346850Y-50008D01*
X345540Y-48842D01*
X344666Y-46800D01*
X344230Y-44467D01*
X344666Y-42133D01*
X345540Y-40092D01*
X346850Y-38925D01*
X348160Y-38634D01*
X349470Y-38925D01*
X350780Y-40092D01*
X351653Y-42133D01*
X351872Y-44467D01*
X351653Y-46800D01*
X350780Y-48842D01*
X349470Y-50008D01*
X348160Y-50300D01*
G01X362603D02*
Y-38634D01*
G01Y-40967D02*
X363695Y-39800D01*
X364787Y-38925D01*
X366315Y-38634D01*
X367406Y-38925D01*
X368717Y-39800D01*
G01X396075Y-55550D02*
X397385Y-56133D01*
X399132Y-55550D01*
X400223Y-54384D01*
X401097Y-52925D01*
X402406Y-48259D01*
X405245Y-38634D01*
G01X398258D02*
X402406Y-48259D01*
G01X418160Y-50300D02*
X416850Y-50008D01*
X415540Y-48842D01*
X414666Y-46800D01*
X414230Y-44467D01*
X414666Y-42133D01*
X415540Y-40092D01*
X416850Y-38925D01*
X418160Y-38634D01*
X419470Y-38925D01*
X420780Y-40092D01*
X421653Y-42133D01*
X421872Y-44467D01*
X421653Y-46800D01*
X420780Y-48842D01*
X419470Y-50008D01*
X418160Y-50300D01*
G01X431948Y-38634D02*
Y-46800D01*
X432822Y-48842D01*
X434132Y-50008D01*
X435660Y-50300D01*
X437188Y-50008D01*
X438498Y-48842D01*
X439372Y-46800D01*
G01Y-50300D02*
Y-38634D01*
G01X450103Y-50300D02*
Y-38634D01*
G01Y-40967D02*
X451195Y-39800D01*
X452287Y-38925D01*
X453815Y-38634D01*
X454906Y-38925D01*
X456217Y-39800D01*
G01X485103Y-50300D02*
Y-38634D01*
G01Y-40967D02*
X486195Y-39800D01*
X487287Y-38925D01*
X488815Y-38634D01*
X489906Y-38925D01*
X491217Y-39800D01*
G01X502385Y-42425D02*
X509372D01*
X508717Y-40383D01*
X507625Y-39217D01*
X506097Y-38634D01*
X504568Y-38925D01*
X503258Y-39800D01*
X502385Y-41842D01*
X501948Y-43592D01*
Y-45342D01*
X502385Y-47092D01*
X503477Y-48842D01*
X504787Y-50008D01*
X506315Y-50300D01*
X507843Y-49717D01*
X509372Y-47967D01*
G01X521850Y-50300D02*
Y-35425D01*
X522287Y-33967D01*
X523160Y-33092D01*
X524470Y-32800D01*
X525780Y-33383D01*
X526435Y-34842D01*
G01X523815Y-39800D02*
X519448D01*
G01X537385Y-42425D02*
X544372D01*
X543717Y-40383D01*
X542625Y-39217D01*
X541097Y-38634D01*
X539568Y-38925D01*
X538258Y-39800D01*
X537385Y-41842D01*
X536948Y-43592D01*
Y-45342D01*
X537385Y-47092D01*
X538477Y-48842D01*
X539787Y-50008D01*
X541315Y-50300D01*
X542843Y-49717D01*
X544372Y-47967D01*
G01X555103Y-50300D02*
Y-38634D01*
G01Y-40967D02*
X556195Y-39800D01*
X557287Y-38925D01*
X558815Y-38634D01*
X559906Y-38925D01*
X561217Y-39800D01*
G01X572385Y-42425D02*
X579372D01*
X578717Y-40383D01*
X577625Y-39217D01*
X576097Y-38634D01*
X574568Y-38925D01*
X573258Y-39800D01*
X572385Y-41842D01*
X571948Y-43592D01*
Y-45342D01*
X572385Y-47092D01*
X573477Y-48842D01*
X574787Y-50008D01*
X576315Y-50300D01*
X577843Y-49717D01*
X579372Y-47967D01*
G01X589448Y-50300D02*
Y-38634D01*
G01Y-41550D02*
X590322Y-40092D01*
X591632Y-38925D01*
X593378Y-38634D01*
X594906Y-38925D01*
X596217Y-40092D01*
X596872Y-42133D01*
Y-50300D01*
G01X614153Y-40092D02*
X612625Y-38925D01*
X611315Y-38634D01*
X609568Y-39217D01*
X608258Y-40383D01*
X607385Y-42425D01*
X607166Y-44467D01*
X607385Y-46509D01*
X608258Y-48259D01*
X609568Y-49717D01*
X611315Y-50300D01*
X612843Y-49717D01*
X614153Y-48550D01*
G01X624885Y-42425D02*
X631872D01*
X631217Y-40383D01*
X630125Y-39217D01*
X628597Y-38634D01*
X627068Y-38925D01*
X625758Y-39800D01*
X624885Y-41842D01*
X624448Y-43592D01*
Y-45342D01*
X624885Y-47092D01*
X625977Y-48842D01*
X627287Y-50008D01*
X628815Y-50300D01*
X630343Y-49717D01*
X631872Y-47967D01*
G01X663160Y-32800D02*
Y-50300D01*
G01X660103Y-38634D02*
X666217D01*
G01X680660Y-50300D02*
X679350Y-50008D01*
X678040Y-48842D01*
X677166Y-46800D01*
X676730Y-44467D01*
X677166Y-42133D01*
X678040Y-40092D01*
X679350Y-38925D01*
X680660Y-38634D01*
X681970Y-38925D01*
X683280Y-40092D01*
X684153Y-42133D01*
X684372Y-44467D01*
X684153Y-46800D01*
X683280Y-48842D01*
X681970Y-50008D01*
X680660Y-50300D01*
G01X714350D02*
Y-35425D01*
X714787Y-33967D01*
X715660Y-33092D01*
X716970Y-32800D01*
X718280Y-33383D01*
X718935Y-34842D01*
G01X716315Y-39800D02*
X711948D01*
G01X733160Y-38634D02*
Y-50300D01*
G01Y-33967D02*
X732723Y-33675D01*
Y-33092D01*
X733160Y-32800D01*
X733597Y-33092D01*
Y-33675D01*
X733160Y-33967D01*
G01X746948Y-50300D02*
Y-38634D01*
G01Y-41550D02*
X747822Y-40092D01*
X749132Y-38925D01*
X750878Y-38634D01*
X752406Y-38925D01*
X753717Y-40092D01*
X754372Y-42133D01*
Y-50300D01*
G01X772090Y-32800D02*
Y-50300D01*
G01Y-47676D02*
X771217Y-49134D01*
X769906Y-50008D01*
X768378Y-50300D01*
X766632Y-49717D01*
X765322Y-48259D01*
X764448Y-46509D01*
X764230Y-44467D01*
X764448Y-42425D01*
X765322Y-40675D01*
X766632Y-39217D01*
X768378Y-38634D01*
X769906Y-38925D01*
X770998Y-39509D01*
X772090Y-40675D01*
G01X803160Y-32800D02*
Y-50300D01*
G01X800103Y-38634D02*
X806217D01*
G01X816948Y-50300D02*
Y-32800D01*
G01Y-41258D02*
X818040Y-39800D01*
X819132Y-38925D01*
X820878Y-38634D01*
X822188Y-38925D01*
X823717Y-40092D01*
X824372Y-41842D01*
Y-50300D01*
G01X834885Y-42425D02*
X841872D01*
X841217Y-40383D01*
X840125Y-39217D01*
X838597Y-38634D01*
X837068Y-38925D01*
X835758Y-39800D01*
X834885Y-41842D01*
X834448Y-43592D01*
Y-45342D01*
X834885Y-47092D01*
X835977Y-48842D01*
X837287Y-50008D01*
X838815Y-50300D01*
X840343Y-49717D01*
X841872Y-47967D01*
G01X868357Y-50300D02*
Y-32800D01*
X872723D01*
X874470Y-33675D01*
X875780Y-34842D01*
X876872Y-36591D01*
X877745Y-38634D01*
X877963Y-41550D01*
X877745Y-44467D01*
X876872Y-46509D01*
X875780Y-48259D01*
X874470Y-49425D01*
X872723Y-50300D01*
X868357D01*
G01X886293D02*
Y-32800D01*
X891533D01*
X893280Y-33675D01*
X894590Y-35717D01*
X895027Y-38050D01*
X894590Y-40383D01*
X893498Y-42133D01*
X891533Y-43009D01*
X886293D01*
G01X925660Y-38634D02*
Y-50300D01*
G01Y-33967D02*
X925223Y-33675D01*
Y-33092D01*
X925660Y-32800D01*
X926097Y-33092D01*
Y-33675D01*
X925660Y-33967D01*
G01X936610Y-50300D02*
Y-38634D01*
G01Y-41842D02*
X937265Y-40383D01*
X938357Y-39217D01*
X939885Y-38634D01*
X941413Y-39217D01*
X942505Y-40383D01*
X943160Y-41842D01*
Y-50300D01*
G01Y-41842D02*
X943815Y-40383D01*
X944906Y-39217D01*
X946435Y-38634D01*
X947963Y-39217D01*
X949055Y-40383D01*
X949710Y-42133D01*
Y-50300D01*
G01X956730Y-56133D02*
Y-38634D01*
G01Y-41258D02*
X957822Y-39800D01*
X958913Y-38925D01*
X960660Y-38634D01*
X962188Y-38925D01*
X963717Y-40383D01*
X964372Y-42425D01*
X964590Y-44467D01*
X964372Y-46509D01*
X963717Y-48550D01*
X962406Y-49717D01*
X960660Y-50300D01*
X959132Y-50008D01*
X957603Y-49134D01*
X956730Y-47967D01*
G01X974885Y-42425D02*
X981872D01*
X981217Y-40383D01*
X980125Y-39217D01*
X978597Y-38634D01*
X977068Y-38925D01*
X975758Y-39800D01*
X974885Y-41842D01*
X974448Y-43592D01*
Y-45342D01*
X974885Y-47092D01*
X975977Y-48842D01*
X977287Y-50008D01*
X978815Y-50300D01*
X980343Y-49717D01*
X981872Y-47967D01*
G01X999590Y-32800D02*
Y-50300D01*
G01Y-47676D02*
X998717Y-49134D01*
X997406Y-50008D01*
X995878Y-50300D01*
X994132Y-49717D01*
X992822Y-48259D01*
X991948Y-46509D01*
X991730Y-44467D01*
X991948Y-42425D01*
X992822Y-40675D01*
X994132Y-39217D01*
X995878Y-38634D01*
X997406Y-38925D01*
X998498Y-39509D01*
X999590Y-40675D01*
G01X1017090Y-50300D02*
Y-38634D01*
G01Y-40675D02*
X1016217Y-39509D01*
X1014906Y-38925D01*
X1013378Y-38634D01*
X1011850Y-39217D01*
X1010540Y-40383D01*
X1009666Y-42133D01*
X1009230Y-44467D01*
X1009666Y-46800D01*
X1010540Y-48550D01*
X1011850Y-49717D01*
X1013378Y-50300D01*
X1014906Y-50008D01*
X1016217Y-49134D01*
X1017090Y-47967D01*
G01X1026948Y-50300D02*
Y-38634D01*
G01Y-41550D02*
X1027822Y-40092D01*
X1029132Y-38925D01*
X1030878Y-38634D01*
X1032406Y-38925D01*
X1033717Y-40092D01*
X1034372Y-42133D01*
Y-50300D01*
G01X1051653Y-40092D02*
X1050125Y-38925D01*
X1048815Y-38634D01*
X1047068Y-39217D01*
X1045758Y-40383D01*
X1044885Y-42425D01*
X1044666Y-44467D01*
X1044885Y-46509D01*
X1045758Y-48259D01*
X1047068Y-49717D01*
X1048815Y-50300D01*
X1050343Y-49717D01*
X1051653Y-48550D01*
G01X1062385Y-42425D02*
X1069372D01*
X1068717Y-40383D01*
X1067625Y-39217D01*
X1066097Y-38634D01*
X1064568Y-38925D01*
X1063258Y-39800D01*
X1062385Y-41842D01*
X1061948Y-43592D01*
Y-45342D01*
X1062385Y-47092D01*
X1063477Y-48842D01*
X1064787Y-50008D01*
X1066315Y-50300D01*
X1067843Y-49717D01*
X1069372Y-47967D01*
G01X1100660Y-32800D02*
Y-50300D01*
G01X1097603Y-38634D02*
X1103717D01*
G01X1115103Y-50300D02*
Y-38634D01*
G01Y-40967D02*
X1116195Y-39800D01*
X1117287Y-38925D01*
X1118815Y-38634D01*
X1119906Y-38925D01*
X1121217Y-39800D01*
G01X1139590Y-50300D02*
Y-38634D01*
G01Y-40675D02*
X1138717Y-39509D01*
X1137406Y-38925D01*
X1135878Y-38634D01*
X1134350Y-39217D01*
X1133040Y-40383D01*
X1132166Y-42133D01*
X1131730Y-44467D01*
X1132166Y-46800D01*
X1133040Y-48550D01*
X1134350Y-49717D01*
X1135878Y-50300D01*
X1137406Y-50008D01*
X1138717Y-49134D01*
X1139590Y-47967D01*
G01X1156653Y-40092D02*
X1155125Y-38925D01*
X1153815Y-38634D01*
X1152068Y-39217D01*
X1150758Y-40383D01*
X1149885Y-42425D01*
X1149666Y-44467D01*
X1149885Y-46509D01*
X1150758Y-48259D01*
X1152068Y-49717D01*
X1153815Y-50300D01*
X1155343Y-49717D01*
X1156653Y-48550D01*
G01X1167385Y-42425D02*
X1174372D01*
X1173717Y-40383D01*
X1172625Y-39217D01*
X1171097Y-38634D01*
X1169568Y-38925D01*
X1168258Y-39800D01*
X1167385Y-41842D01*
X1166948Y-43592D01*
Y-45342D01*
X1167385Y-47092D01*
X1168477Y-48842D01*
X1169787Y-50008D01*
X1171315Y-50300D01*
X1172843Y-49717D01*
X1174372Y-47967D01*
G01X1184885Y-48259D02*
X1185977Y-49425D01*
X1187505Y-50300D01*
X1188815D01*
X1190125Y-49717D01*
X1190998Y-48842D01*
X1191435Y-47676D01*
X1191217Y-45925D01*
X1190343Y-45050D01*
X1186413Y-43300D01*
X1185540Y-41258D01*
X1185977Y-39800D01*
X1186850Y-38925D01*
X1188160Y-38634D01*
X1189470Y-38925D01*
X1190780Y-39800D01*
G01X1223160Y-38634D02*
Y-50300D01*
G01Y-33967D02*
X1222723Y-33675D01*
Y-33092D01*
X1223160Y-32800D01*
X1223597Y-33092D01*
Y-33675D01*
X1223160Y-33967D01*
G01X1236948Y-50300D02*
Y-38634D01*
G01Y-41550D02*
X1237822Y-40092D01*
X1239132Y-38925D01*
X1240878Y-38634D01*
X1242406Y-38925D01*
X1243717Y-40092D01*
X1244372Y-42133D01*
Y-50300D01*
G01X1275660D02*
Y-32800D01*
G01X1297090Y-50300D02*
Y-38634D01*
G01Y-40675D02*
X1296217Y-39509D01*
X1294906Y-38925D01*
X1293378Y-38634D01*
X1291850Y-39217D01*
X1290540Y-40383D01*
X1289666Y-42133D01*
X1289230Y-44467D01*
X1289666Y-46800D01*
X1290540Y-48550D01*
X1291850Y-49717D01*
X1293378Y-50300D01*
X1294906Y-50008D01*
X1296217Y-49134D01*
X1297090Y-47967D01*
G01X1306075Y-55550D02*
X1307385Y-56133D01*
X1309132Y-55550D01*
X1310223Y-54384D01*
X1311097Y-52925D01*
X1312406Y-48259D01*
X1315245Y-38634D01*
G01X1308258D02*
X1312406Y-48259D01*
G01X1324885Y-42425D02*
X1331872D01*
X1331217Y-40383D01*
X1330125Y-39217D01*
X1328597Y-38634D01*
X1327068Y-38925D01*
X1325758Y-39800D01*
X1324885Y-41842D01*
X1324448Y-43592D01*
Y-45342D01*
X1324885Y-47092D01*
X1325977Y-48842D01*
X1327287Y-50008D01*
X1328815Y-50300D01*
X1330343Y-49717D01*
X1331872Y-47967D01*
G01X1342603Y-50300D02*
Y-38634D01*
G01Y-40967D02*
X1343695Y-39800D01*
X1344787Y-38925D01*
X1346315Y-38634D01*
X1347406Y-38925D01*
X1348717Y-39800D01*
G01X1376293Y-32800D02*
Y-50300D01*
X1385027D01*
G01X1393357Y-46800D02*
X1394666Y-48842D01*
X1396413Y-50008D01*
X1398378Y-50300D01*
X1400125Y-50008D01*
X1401872Y-48550D01*
X1402963Y-46800D01*
X1403182Y-45050D01*
X1402745Y-43009D01*
X1401217Y-41550D01*
X1399688Y-40967D01*
X1397723D01*
G01X1399688D02*
X1400998Y-40092D01*
X1402090Y-38634D01*
X1402527Y-36884D01*
X1402090Y-35133D01*
X1400998Y-33675D01*
X1399033Y-32800D01*
X1397068Y-33092D01*
X1395103Y-34259D01*
G01X1415660Y-50883D02*
X1415223Y-50592D01*
Y-50008D01*
X1415660Y-49717D01*
X1416097Y-50008D01*
Y-50592D01*
X1415660Y-50883D01*
G01X617008Y706896D02*
Y724396D01*
X621374D01*
X623121Y723521D01*
X624431Y722354D01*
X625523Y720605D01*
X626396Y718562D01*
X626614Y715646D01*
X626396Y712729D01*
X625523Y710687D01*
X624431Y708937D01*
X623121Y707771D01*
X621374Y706896D01*
X617008D01*
G01X634944D02*
Y724396D01*
X640184D01*
X641931Y723521D01*
X643241Y721479D01*
X643678Y719146D01*
X643241Y716813D01*
X642149Y715063D01*
X640184Y714187D01*
X634944D01*
G01X671691Y724396D02*
X676931D01*
G01X674311D02*
Y706896D01*
G01X671691D02*
X676931D01*
G01X686134D02*
Y724396D01*
X691811Y709813D01*
X697488Y724396D01*
Y706896D01*
G01X704944D02*
Y724396D01*
X710184D01*
X711931Y723521D01*
X713241Y721479D01*
X713678Y719146D01*
X713241Y716813D01*
X712149Y715063D01*
X710184Y714187D01*
X704944D01*
G01X731178Y706896D02*
X722444D01*
Y724396D01*
X731178D01*
G01X727684Y715938D02*
X722444D01*
G01X739508Y706896D02*
Y724396D01*
X743874D01*
X745621Y723521D01*
X746931Y722354D01*
X748023Y720605D01*
X748896Y718562D01*
X749114Y715646D01*
X748896Y712729D01*
X748023Y710687D01*
X746931Y708937D01*
X745621Y707771D01*
X743874Y706896D01*
X739508D01*
G01X756352D02*
X761811Y724396D01*
X767270Y706896D01*
G01X765304Y713021D02*
X758317D01*
G01X774289Y706896D02*
Y724396D01*
X784333Y706896D01*
Y724396D01*
G01X801614Y722937D02*
X800304Y723813D01*
X798776Y724396D01*
X797029D01*
X795064Y723521D01*
X793536Y722063D01*
X792444Y720312D01*
X791571Y717396D01*
X791352Y714771D01*
X791789Y712146D01*
X792444Y710396D01*
X793754Y708646D01*
X795283Y707479D01*
X796811Y706896D01*
X798339D01*
X799868Y707479D01*
X801178Y708354D01*
X802270Y709520D01*
G01X818678Y706896D02*
X809944D01*
Y724396D01*
X818678D01*
G01X815184Y715938D02*
X809944D01*
G01X849311Y724396D02*
Y706896D01*
G01X844289Y724396D02*
X854333D01*
G01X861352Y706896D02*
X866811Y724396D01*
X872270Y706896D01*
G01X870304Y713021D02*
X863317D01*
G01X886057Y716229D02*
X886931Y717104D01*
X887586Y718562D01*
X888023Y720605D01*
X887586Y722354D01*
X886713Y723521D01*
X885184Y724396D01*
X879289D01*
Y706896D01*
X886494D01*
X888023Y708062D01*
X888896Y709813D01*
X889333Y711854D01*
X888896Y713896D01*
X887586Y715646D01*
X886057Y716229D01*
X879289D01*
G01X897444Y724396D02*
Y706896D01*
X906178D01*
G01X923678D02*
X914944D01*
Y724396D01*
X923678D01*
G01X920184Y715938D02*
X914944D01*
G01X936811Y706313D02*
X936374Y706604D01*
Y707188D01*
X936811Y707479D01*
X937248Y707188D01*
Y706604D01*
X936811Y706313D01*
G01Y714187D02*
X936374Y714479D01*
Y715063D01*
X936811Y715354D01*
X937248Y715063D01*
Y714479D01*
X936811Y714187D01*
G01X967444Y724396D02*
Y706896D01*
X976178D01*
G01X984508Y710396D02*
X985817Y708354D01*
X987564Y707188D01*
X989529Y706896D01*
X991276Y707188D01*
X993023Y708646D01*
X994114Y710396D01*
X994333Y712146D01*
X993896Y714187D01*
X992368Y715646D01*
X990839Y716229D01*
X988874D01*
G01X990839D02*
X992149Y717104D01*
X993241Y718562D01*
X993678Y720312D01*
X993241Y722063D01*
X992149Y723521D01*
X990184Y724396D01*
X988219Y724104D01*
X986254Y722937D01*
G01X638891Y689746D02*
X644131D01*
G01X641511D02*
Y672246D01*
G01X638891D02*
X644131D01*
G01X653334D02*
Y689746D01*
X659011Y675163D01*
X664688Y689746D01*
Y672246D01*
G01X672144D02*
Y689746D01*
X677384D01*
X679131Y688871D01*
X680441Y686829D01*
X680878Y684496D01*
X680441Y682163D01*
X679349Y680413D01*
X677384Y679537D01*
X672144D01*
G01X692919Y666413D02*
X690736Y669329D01*
X689644Y672246D01*
Y683912D01*
X690736Y686829D01*
X692919Y689746D01*
G01X711511Y672246D02*
X709764Y672538D01*
X708236Y673704D01*
X706926Y675454D01*
X706052Y677496D01*
X705616Y679829D01*
Y682163D01*
X706052Y684496D01*
X706926Y686538D01*
X708236Y688287D01*
X709764Y689454D01*
X711511Y689746D01*
X713257Y689454D01*
X714786Y688287D01*
X716096Y686538D01*
X716970Y684496D01*
X717406Y682163D01*
Y679829D01*
X716970Y677496D01*
X716096Y675454D01*
X714786Y673704D01*
X713257Y672538D01*
X711511Y672246D01*
G01X725299D02*
Y689746D01*
G01Y681288D02*
X726391Y682746D01*
X727483Y683621D01*
X729229Y683912D01*
X730539Y683621D01*
X732068Y682454D01*
X732723Y680704D01*
Y672246D01*
G01X739961D02*
Y683912D01*
G01Y680704D02*
X740616Y682163D01*
X741708Y683329D01*
X743236Y683912D01*
X744764Y683329D01*
X745856Y682163D01*
X746511Y680704D01*
Y672246D01*
G01Y680704D02*
X747166Y682163D01*
X748257Y683329D01*
X749786Y683912D01*
X751314Y683329D01*
X752406Y682163D01*
X753061Y680413D01*
Y672246D01*
G01X765103Y666413D02*
X767286Y669329D01*
X768378Y672246D01*
Y683912D01*
X767286Y686829D01*
X765103Y689746D01*
G01X676511Y637596D02*
X678039Y637888D01*
X679786Y638762D01*
X680878Y640220D01*
X681314Y642263D01*
X680878Y644304D01*
X679568Y646054D01*
X677603Y646929D01*
X675419D01*
X674109Y647513D01*
X673017Y648971D01*
X672581Y651012D01*
X673236Y653054D01*
X674764Y654513D01*
X676511Y655096D01*
X678257Y654513D01*
X679786Y653054D01*
X680441Y651012D01*
X680004Y648971D01*
X678913Y647513D01*
X677603Y646929D01*
X675419D01*
X673454Y646054D01*
X672144Y644304D01*
X671708Y642263D01*
X672144Y640220D01*
X673236Y638762D01*
X674983Y637888D01*
X676511Y637596D01*
G01X689208Y640220D02*
X690517Y638762D01*
X692046Y637888D01*
X694011Y637596D01*
X695976Y638179D01*
X697504Y639346D01*
X698596Y641387D01*
X698814Y643721D01*
X698378Y646054D01*
X697286Y647513D01*
X695757Y648679D01*
X694229Y648971D01*
X692701Y648679D01*
X690736Y647513D01*
X691391Y655096D01*
X697286D01*
G01X711511Y637013D02*
X711074Y637304D01*
Y637888D01*
X711511Y638179D01*
X711948Y637888D01*
Y637304D01*
X711511Y637013D01*
G01X729011Y655096D02*
X727264Y654513D01*
X725954Y653054D01*
X725081Y651305D01*
X724426Y648971D01*
X724208Y646346D01*
X724426Y643721D01*
X725081Y641387D01*
X725954Y639637D01*
X727264Y638179D01*
X729011Y637596D01*
X730757Y638179D01*
X732068Y639637D01*
X732941Y641387D01*
X733596Y643721D01*
X733814Y646346D01*
X733596Y648971D01*
X732941Y651305D01*
X732068Y653054D01*
X730757Y654513D01*
X729011Y655096D01*
G01X844961Y689746D02*
X848017Y672246D01*
X851511Y689746D01*
X855004Y672246D01*
X858061Y689746D01*
G01X866391D02*
X871631D01*
G01X869011D02*
Y672246D01*
G01X866391D02*
X871631D01*
G01X881708D02*
Y689746D01*
X886074D01*
X887821Y688871D01*
X889131Y687704D01*
X890223Y685955D01*
X891096Y683912D01*
X891314Y680996D01*
X891096Y678079D01*
X890223Y676037D01*
X889131Y674287D01*
X887821Y673121D01*
X886074Y672246D01*
X881708D01*
G01X904011Y689746D02*
Y672246D01*
G01X898989Y689746D02*
X909033D01*
G01X916926Y672246D02*
Y689746D01*
G01X926096D02*
Y672246D01*
G01Y680996D02*
X916926D01*
G01X937919Y666413D02*
X935736Y669329D01*
X934644Y672246D01*
Y683912D01*
X935736Y686829D01*
X937919Y689746D01*
G01X949961Y672246D02*
Y683912D01*
G01Y680704D02*
X950616Y682163D01*
X951708Y683329D01*
X953236Y683912D01*
X954764Y683329D01*
X955856Y682163D01*
X956511Y680704D01*
Y672246D01*
G01Y680704D02*
X957166Y682163D01*
X958257Y683329D01*
X959786Y683912D01*
X961314Y683329D01*
X962406Y682163D01*
X963061Y680413D01*
Y672246D01*
G01X974011Y683912D02*
Y672246D01*
G01Y688579D02*
X973574Y688871D01*
Y689454D01*
X974011Y689746D01*
X974448Y689454D01*
Y688871D01*
X974011Y688579D01*
G01X991511Y672246D02*
Y689746D01*
G01X1005736Y674287D02*
X1006828Y673121D01*
X1008356Y672246D01*
X1009666D01*
X1010976Y672829D01*
X1011849Y673704D01*
X1012286Y674870D01*
X1012068Y676621D01*
X1011194Y677496D01*
X1007264Y679246D01*
X1006391Y681288D01*
X1006828Y682746D01*
X1007701Y683621D01*
X1009011Y683912D01*
X1010321Y683621D01*
X1011631Y682746D01*
G01X1027603Y666413D02*
X1029786Y669329D01*
X1030878Y672246D01*
Y683912D01*
X1029786Y686829D01*
X1027603Y689746D01*
G01X881708Y640220D02*
X883017Y638762D01*
X884546Y637888D01*
X886511Y637596D01*
X888476Y638179D01*
X890004Y639346D01*
X891096Y641387D01*
X891314Y643721D01*
X890878Y646054D01*
X889786Y647513D01*
X888257Y648679D01*
X886729Y648971D01*
X885201Y648679D01*
X883236Y647513D01*
X883891Y655096D01*
X889786D01*
G01X904011Y637013D02*
X903574Y637304D01*
Y637888D01*
X904011Y638179D01*
X904448Y637888D01*
Y637304D01*
X904011Y637013D01*
G01X917363Y644887D02*
X918891Y646929D01*
X920201Y648096D01*
X921948Y648679D01*
X923476Y648096D01*
X924568Y646929D01*
X925441Y645179D01*
X925659Y643138D01*
X925441Y641387D01*
X924568Y639637D01*
X923257Y638179D01*
X921729Y637596D01*
X919983Y638179D01*
X918454Y639929D01*
X917581Y642554D01*
X917363Y645471D01*
X917799Y649262D01*
X918454Y651305D01*
X919546Y653346D01*
X921074Y654804D01*
X922603Y655096D01*
X924131Y654513D01*
X925223Y653054D01*
G01X935081Y637013D02*
X942941Y655096D01*
G01X956074Y637596D02*
X956511Y641387D01*
X957166Y644596D01*
X958039Y647513D01*
X959131Y650721D01*
X960878Y655096D01*
X952144D01*
G01X974011Y637013D02*
X973574Y637304D01*
Y637888D01*
X974011Y638179D01*
X974448Y637888D01*
Y637304D01*
X974011Y637013D01*
G01X991511Y655096D02*
X989764Y654513D01*
X988454Y653054D01*
X987581Y651305D01*
X986926Y648971D01*
X986708Y646346D01*
X986926Y643721D01*
X987581Y641387D01*
X988454Y639637D01*
X989764Y638179D01*
X991511Y637596D01*
X993257Y638179D01*
X994568Y639637D01*
X995441Y641387D01*
X996096Y643721D01*
X996314Y646346D01*
X996096Y648971D01*
X995441Y651305D01*
X994568Y653054D01*
X993257Y654513D01*
X991511Y655096D01*
G01X1114011Y689746D02*
Y672246D01*
G01X1108989Y689746D02*
X1119033D01*
G01X1131511Y672246D02*
Y680121D01*
X1127144Y689746D01*
G01X1135878D02*
X1131511Y680121D01*
G01X1144644Y672246D02*
Y689746D01*
X1149884D01*
X1151631Y688871D01*
X1152941Y686829D01*
X1153378Y684496D01*
X1152941Y682163D01*
X1151849Y680413D01*
X1149884Y679537D01*
X1144644D01*
G01X1170878Y672246D02*
X1162144D01*
Y689746D01*
X1170878D01*
G01X1167384Y681288D02*
X1162144D01*
G01X1126708Y637596D02*
Y655096D01*
X1131074D01*
X1132821Y654221D01*
X1134131Y653054D01*
X1135223Y651305D01*
X1136096Y649262D01*
X1136314Y646346D01*
X1136096Y643429D01*
X1135223Y641387D01*
X1134131Y639637D01*
X1132821Y638471D01*
X1131074Y637596D01*
X1126708D01*
G01X1144644D02*
Y655096D01*
X1149884D01*
X1151631Y654221D01*
X1152941Y652179D01*
X1153378Y649846D01*
X1152941Y647513D01*
X1151849Y645763D01*
X1149884Y644887D01*
X1144644D01*
G01X1214644Y672246D02*
Y689746D01*
X1220103D01*
X1221849Y688871D01*
X1222941Y687704D01*
X1223378Y685371D01*
X1222941Y683037D01*
X1221631Y681579D01*
X1220103Y680704D01*
X1214644D01*
G01X1220103D02*
X1223378Y672246D01*
G01X1233236Y680121D02*
X1240223D01*
X1239568Y682163D01*
X1238476Y683329D01*
X1236948Y683912D01*
X1235419Y683621D01*
X1234109Y682746D01*
X1233236Y680704D01*
X1232799Y678954D01*
Y677204D01*
X1233236Y675454D01*
X1234328Y673704D01*
X1235638Y672538D01*
X1237166Y672246D01*
X1238694Y672829D01*
X1240223Y674579D01*
G01X1252701Y672246D02*
Y687121D01*
X1253138Y688579D01*
X1254011Y689454D01*
X1255321Y689746D01*
X1256631Y689163D01*
X1257286Y687704D01*
G01X1254666Y682746D02*
X1250299D01*
G01X1271511Y671663D02*
X1271074Y671954D01*
Y672538D01*
X1271511Y672829D01*
X1271948Y672538D01*
Y671954D01*
X1271511Y671663D01*
G01X1302144Y672246D02*
Y689746D01*
X1307384D01*
X1309131Y688871D01*
X1310441Y686829D01*
X1310878Y684496D01*
X1310441Y682163D01*
X1309349Y680413D01*
X1307384Y679537D01*
X1302144D01*
G01X1324011Y672246D02*
Y689746D01*
G01X1345441Y672246D02*
Y683912D01*
G01Y681871D02*
X1344568Y683037D01*
X1343257Y683621D01*
X1341729Y683912D01*
X1340201Y683329D01*
X1338891Y682163D01*
X1338017Y680413D01*
X1337581Y678079D01*
X1338017Y675746D01*
X1338891Y673996D01*
X1340201Y672829D01*
X1341729Y672246D01*
X1343257Y672538D01*
X1344568Y673412D01*
X1345441Y674579D01*
G01X1355299Y672246D02*
Y683912D01*
G01Y680996D02*
X1356173Y682454D01*
X1357483Y683621D01*
X1359229Y683912D01*
X1360757Y683621D01*
X1362068Y682454D01*
X1362723Y680413D01*
Y672246D01*
G01X1373236Y680121D02*
X1380223D01*
X1379568Y682163D01*
X1378476Y683329D01*
X1376948Y683912D01*
X1375419Y683621D01*
X1374109Y682746D01*
X1373236Y680704D01*
X1372799Y678954D01*
Y677204D01*
X1373236Y675454D01*
X1374328Y673704D01*
X1375638Y672538D01*
X1377166Y672246D01*
X1378694Y672829D01*
X1380223Y674579D01*
G01X1258394Y655096D02*
Y637596D01*
X1267128D01*
G01X1276113Y652179D02*
X1277423Y653929D01*
X1278951Y654804D01*
X1280698Y655096D01*
X1282881Y654513D01*
X1284409Y653054D01*
X1284846Y651305D01*
X1284628Y649554D01*
X1283754Y648096D01*
X1279388Y645179D01*
X1277423Y643138D01*
X1276113Y640220D01*
X1275676Y637596D01*
X1284846D01*
G01X1293831Y637013D02*
X1301691Y655096D01*
G01X1310894D02*
Y637596D01*
X1319628D01*
G01X1327958Y640220D02*
X1329267Y638762D01*
X1330796Y637888D01*
X1332761Y637596D01*
X1334726Y638179D01*
X1336254Y639346D01*
X1337346Y641387D01*
X1337564Y643721D01*
X1337128Y646054D01*
X1336036Y647513D01*
X1334507Y648679D01*
X1332979Y648971D01*
X1331451Y648679D01*
X1329486Y647513D01*
X1330141Y655096D01*
X1336036D01*
G01X1494311Y649262D02*
Y637596D01*
G01Y653929D02*
X1493874Y654221D01*
Y654804D01*
X1494311Y655096D01*
X1494748Y654804D01*
Y654221D01*
X1494311Y653929D01*
G01X1508536Y639637D02*
X1509628Y638471D01*
X1511156Y637596D01*
X1512466D01*
X1513776Y638179D01*
X1514649Y639054D01*
X1515086Y640220D01*
X1514868Y641971D01*
X1513994Y642846D01*
X1510064Y644596D01*
X1509191Y646638D01*
X1509628Y648096D01*
X1510501Y648971D01*
X1511811Y649262D01*
X1513121Y648971D01*
X1514431Y648096D01*
G01X1541789Y637596D02*
Y655096D01*
X1551833Y637596D01*
Y655096D01*
G01X1564311Y637596D02*
X1562564Y637888D01*
X1561036Y639054D01*
X1559726Y640804D01*
X1558852Y642846D01*
X1558416Y645179D01*
Y647513D01*
X1558852Y649846D01*
X1559726Y651888D01*
X1561036Y653637D01*
X1562564Y654804D01*
X1564311Y655096D01*
X1566057Y654804D01*
X1567586Y653637D01*
X1568896Y651888D01*
X1569770Y649846D01*
X1570206Y647513D01*
Y645179D01*
X1569770Y642846D01*
X1568896Y640804D01*
X1567586Y639054D01*
X1566057Y637888D01*
X1564311Y637596D01*
G01X1581811Y655096D02*
Y637596D01*
G01X1576789Y655096D02*
X1586833D01*
G01X1613099Y649262D02*
Y641096D01*
X1613973Y639054D01*
X1615283Y637888D01*
X1616811Y637596D01*
X1618339Y637888D01*
X1619649Y639054D01*
X1620523Y641096D01*
G01Y637596D02*
Y649262D01*
G01X1631036Y639637D02*
X1632128Y638471D01*
X1633656Y637596D01*
X1634966D01*
X1636276Y638179D01*
X1637149Y639054D01*
X1637586Y640220D01*
X1637368Y641971D01*
X1636494Y642846D01*
X1632564Y644596D01*
X1631691Y646638D01*
X1632128Y648096D01*
X1633001Y648971D01*
X1634311Y649262D01*
X1635621Y648971D01*
X1636931Y648096D01*
G01X1648536Y645471D02*
X1655523D01*
X1654868Y647513D01*
X1653776Y648679D01*
X1652248Y649262D01*
X1650719Y648971D01*
X1649409Y648096D01*
X1648536Y646054D01*
X1648099Y644304D01*
Y642554D01*
X1648536Y640804D01*
X1649628Y639054D01*
X1650938Y637888D01*
X1652466Y637596D01*
X1653994Y638179D01*
X1655523Y639929D01*
G01X1673241Y655096D02*
Y637596D01*
G01Y640220D02*
X1672368Y638762D01*
X1671057Y637888D01*
X1669529Y637596D01*
X1667783Y638179D01*
X1666473Y639637D01*
X1665599Y641387D01*
X1665381Y643429D01*
X1665599Y645471D01*
X1666473Y647221D01*
X1667783Y648679D01*
X1669529Y649262D01*
X1671057Y648971D01*
X1672149Y648387D01*
X1673241Y647221D01*
G01X1419508Y671663D02*
X1429114Y684496D01*
G01X1424311Y686829D02*
Y669329D01*
G01X1429114Y671663D02*
X1419508Y684496D01*
G01X1417761Y678079D02*
X1430861D01*
G01X1456473D02*
X1462149D01*
G01X1489508Y672246D02*
Y689746D01*
X1493874D01*
X1495621Y688871D01*
X1496931Y687704D01*
X1498023Y685955D01*
X1498896Y683912D01*
X1499114Y680996D01*
X1498896Y678079D01*
X1498023Y676037D01*
X1496931Y674287D01*
X1495621Y673121D01*
X1493874Y672246D01*
X1489508D01*
G01X1508536Y680121D02*
X1515523D01*
X1514868Y682163D01*
X1513776Y683329D01*
X1512248Y683912D01*
X1510719Y683621D01*
X1509409Y682746D01*
X1508536Y680704D01*
X1508099Y678954D01*
Y677204D01*
X1508536Y675454D01*
X1509628Y673704D01*
X1510938Y672538D01*
X1512466Y672246D01*
X1513994Y672829D01*
X1515523Y674579D01*
G01X1525599Y672246D02*
Y683912D01*
G01Y680996D02*
X1526473Y682454D01*
X1527783Y683621D01*
X1529529Y683912D01*
X1531057Y683621D01*
X1532368Y682454D01*
X1533023Y680413D01*
Y672246D01*
G01X1546811D02*
X1545501Y672538D01*
X1544191Y673704D01*
X1543317Y675746D01*
X1542881Y678079D01*
X1543317Y680413D01*
X1544191Y682454D01*
X1545501Y683621D01*
X1546811Y683912D01*
X1548121Y683621D01*
X1549431Y682454D01*
X1550304Y680413D01*
X1550523Y678079D01*
X1550304Y675746D01*
X1549431Y673704D01*
X1548121Y672538D01*
X1546811Y672246D01*
G01X1564311Y689746D02*
Y672246D01*
G01X1561254Y683912D02*
X1567368D01*
G01X1578536Y680121D02*
X1585523D01*
X1584868Y682163D01*
X1583776Y683329D01*
X1582248Y683912D01*
X1580719Y683621D01*
X1579409Y682746D01*
X1578536Y680704D01*
X1578099Y678954D01*
Y677204D01*
X1578536Y675454D01*
X1579628Y673704D01*
X1580938Y672538D01*
X1582466Y672246D01*
X1583994Y672829D01*
X1585523Y674579D01*
G01X1596036Y674287D02*
X1597128Y673121D01*
X1598656Y672246D01*
X1599966D01*
X1601276Y672829D01*
X1602149Y673704D01*
X1602586Y674870D01*
X1602368Y676621D01*
X1601494Y677496D01*
X1597564Y679246D01*
X1596691Y681288D01*
X1597128Y682746D01*
X1598001Y683621D01*
X1599311Y683912D01*
X1600621Y683621D01*
X1601931Y682746D01*
G01X1634311Y689746D02*
Y672246D01*
G01X1631254Y683912D02*
X1637368D01*
G01X1648099Y672246D02*
Y689746D01*
G01Y681288D02*
X1649191Y682746D01*
X1650283Y683621D01*
X1652029Y683912D01*
X1653339Y683621D01*
X1654868Y682454D01*
X1655523Y680704D01*
Y672246D01*
G01X1673241D02*
Y683912D01*
G01Y681871D02*
X1672368Y683037D01*
X1671057Y683621D01*
X1669529Y683912D01*
X1668001Y683329D01*
X1666691Y682163D01*
X1665817Y680413D01*
X1665381Y678079D01*
X1665817Y675746D01*
X1666691Y673996D01*
X1668001Y672829D01*
X1669529Y672246D01*
X1671057Y672538D01*
X1672368Y673412D01*
X1673241Y674579D01*
G01X1686811Y689746D02*
Y672246D01*
G01X1683754Y683912D02*
X1689868D01*
G01X1721811Y689746D02*
Y672246D01*
G01X1718754Y683912D02*
X1724868D01*
G01X1735599Y672246D02*
Y689746D01*
G01Y681288D02*
X1736691Y682746D01*
X1737783Y683621D01*
X1739529Y683912D01*
X1740839Y683621D01*
X1742368Y682454D01*
X1743023Y680704D01*
Y672246D01*
G01X1756811Y683912D02*
Y672246D01*
G01Y688579D02*
X1756374Y688871D01*
Y689454D01*
X1756811Y689746D01*
X1757248Y689454D01*
Y688871D01*
X1756811Y688579D01*
G01X1771036Y674287D02*
X1772128Y673121D01*
X1773656Y672246D01*
X1774966D01*
X1776276Y672829D01*
X1777149Y673704D01*
X1777586Y674870D01*
X1777368Y676621D01*
X1776494Y677496D01*
X1772564Y679246D01*
X1771691Y681288D01*
X1772128Y682746D01*
X1773001Y683621D01*
X1774311Y683912D01*
X1775621Y683621D01*
X1776931Y682746D01*
G01X1806691Y689746D02*
X1811931D01*
G01X1809311D02*
Y672246D01*
G01X1806691D02*
X1811931D01*
G01X1820261D02*
Y683912D01*
G01Y680704D02*
X1820916Y682163D01*
X1822008Y683329D01*
X1823536Y683912D01*
X1825064Y683329D01*
X1826156Y682163D01*
X1826811Y680704D01*
Y672246D01*
G01Y680704D02*
X1827466Y682163D01*
X1828557Y683329D01*
X1830086Y683912D01*
X1831614Y683329D01*
X1832706Y682163D01*
X1833361Y680413D01*
Y672246D01*
G01X1840381Y666413D02*
Y683912D01*
G01Y681288D02*
X1841473Y682746D01*
X1842564Y683621D01*
X1844311Y683912D01*
X1845839Y683621D01*
X1847368Y682163D01*
X1848023Y680121D01*
X1848241Y678079D01*
X1848023Y676037D01*
X1847368Y673996D01*
X1846057Y672829D01*
X1844311Y672246D01*
X1842783Y672538D01*
X1841254Y673412D01*
X1840381Y674579D01*
G01X1858536Y680121D02*
X1865523D01*
X1864868Y682163D01*
X1863776Y683329D01*
X1862248Y683912D01*
X1860719Y683621D01*
X1859409Y682746D01*
X1858536Y680704D01*
X1858099Y678954D01*
Y677204D01*
X1858536Y675454D01*
X1859628Y673704D01*
X1860938Y672538D01*
X1862466Y672246D01*
X1863994Y672829D01*
X1865523Y674579D01*
G01X1883241Y689746D02*
Y672246D01*
G01Y674870D02*
X1882368Y673412D01*
X1881057Y672538D01*
X1879529Y672246D01*
X1877783Y672829D01*
X1876473Y674287D01*
X1875599Y676037D01*
X1875381Y678079D01*
X1875599Y680121D01*
X1876473Y681871D01*
X1877783Y683329D01*
X1879529Y683912D01*
X1881057Y683621D01*
X1882149Y683037D01*
X1883241Y681871D01*
G01X1900741Y672246D02*
Y683912D01*
G01Y681871D02*
X1899868Y683037D01*
X1898557Y683621D01*
X1897029Y683912D01*
X1895501Y683329D01*
X1894191Y682163D01*
X1893317Y680413D01*
X1892881Y678079D01*
X1893317Y675746D01*
X1894191Y673996D01*
X1895501Y672829D01*
X1897029Y672246D01*
X1898557Y672538D01*
X1899868Y673412D01*
X1900741Y674579D01*
G01X1910599Y672246D02*
Y683912D01*
G01Y680996D02*
X1911473Y682454D01*
X1912783Y683621D01*
X1914529Y683912D01*
X1916057Y683621D01*
X1917368Y682454D01*
X1918023Y680413D01*
Y672246D01*
G01X1935304Y682454D02*
X1933776Y683621D01*
X1932466Y683912D01*
X1930719Y683329D01*
X1929409Y682163D01*
X1928536Y680121D01*
X1928317Y678079D01*
X1928536Y676037D01*
X1929409Y674287D01*
X1930719Y672829D01*
X1932466Y672246D01*
X1933994Y672829D01*
X1935304Y673996D01*
G01X1946036Y680121D02*
X1953023D01*
X1952368Y682163D01*
X1951276Y683329D01*
X1949748Y683912D01*
X1948219Y683621D01*
X1946909Y682746D01*
X1946036Y680704D01*
X1945599Y678954D01*
Y677204D01*
X1946036Y675454D01*
X1947128Y673704D01*
X1948438Y672538D01*
X1949966Y672246D01*
X1951494Y672829D01*
X1953023Y674579D01*
G01X-25590Y9843D02*
G03X-15748Y0I9842J-1D01*
G01X-25590Y89370D02*
Y9843D01*
G01X-23622Y91339D02*
G03X-25590Y89370I1J-1969D01*
G01X-7874Y91339D02*
X-23622D01*
G01X-25590Y109055D02*
G03X-21653Y105118I3937J0D01*
G01X-25590Y357874D02*
Y109055D01*
G01X-21653Y105118D02*
X261811D01*
G01X-25590Y371654D02*
G03X-23622Y369685I1968J-1D01*
G01X-21653Y361811D02*
G03X-25590Y357874I0J-3937D01*
G01X1969Y361811D02*
X-21653D01*
G01X-7874Y369685D02*
X-23622D01*
G01X-25590Y459055D02*
Y371654D01*
G01X-23622Y461024D02*
G03X-25590Y459055I1J-1969D01*
G01X-7874Y461024D02*
X-23622D01*
G01X-25590Y478740D02*
G03X-21653Y474803I3937J0D01*
G01X-25590Y727559D02*
Y478740D01*
G01X-21653Y474803D02*
X261811D01*
G01X-21653Y731496D02*
G03X-25590Y727559I0J-3937D01*
G01X1969Y731496D02*
X-21653D01*
G01X-11811Y0D02*
G03X-7874Y3937I0J3937D01*
G01X-11811Y0D02*
X-15748D01*
G01X0Y3937D02*
G03X3937Y0I3937J0D01*
G01X-7874Y33071D02*
Y3937D01*
G01X0Y87402D02*
Y3937D01*
G01Y33071D02*
G03X-7874I-3937J0D01*
G01Y58268D02*
G03X0I3937J0D01*
G01X-7874Y91339D02*
Y58268D01*
G01X3937Y91339D02*
G03X0Y87402I0J-3937D01*
G01X5906Y357874D02*
G03X1969Y361811I-3937J0D01*
G01X0Y373622D02*
G03X3937Y369685I3937J0D01*
G01X-7874Y402756D02*
Y369685D01*
G01X0Y457087D02*
Y373622D01*
G01Y402756D02*
G03X-7874I-3937J0D01*
G01Y427953D02*
G03X0I3937J0D01*
G01X-7874Y461024D02*
Y427953D01*
G01X3937Y461024D02*
G03X0Y457087I0J-3937D01*
G01X5906Y727559D02*
G03X1969Y731496I-3937J0D01*
G01X3937Y0D02*
X372048D01*
G01X192914Y91339D02*
X3937D01*
G01X5906Y290748D02*
G03X9843Y286811I3937J0D01*
G01X5906Y357874D02*
Y290748D01*
G01X69488Y286811D02*
X9843D01*
G01X13780Y315650D02*
Y294685D01*
G01X69488D02*
X13780D01*
G01Y315650D02*
G03X5906I-3937J0D01*
G01Y340847D02*
G03X13780I3937J0D01*
G01Y361811D02*
Y340847D01*
G01X3937Y369685D02*
X372048D01*
G01X43307Y361811D02*
X13780D01*
G01X192914Y461024D02*
X3937D01*
G01X5906Y660433D02*
G03X9843Y656496I3937J0D01*
G01X5906Y727559D02*
Y660433D01*
G01X69488Y656496D02*
X9843D01*
G01X13780Y685335D02*
Y664370D01*
G01X69488D02*
X13780D01*
G01Y685335D02*
G03X5906I-3937J0D01*
G01Y710532D02*
G03X13780I3937J0D01*
G01Y729528D02*
Y710532D01*
G01X15748Y731496D02*
G03X13780Y729528I0J-1968D01*
G01X44819Y731496D02*
X15748D01*
G01X43307Y361811D02*
G03Y369685I0J3937D01*
G01X46675Y730184D02*
G03X44819Y731496I-1856J-657D01*
G01X46675Y730184D02*
G03X54098I3712J1313D01*
G01X53150Y181697D02*
G03X55118Y179729I1968J0D01*
G01X53150Y195477D02*
Y181697D01*
G01X55118Y179729D02*
X161418D01*
G01X55118Y197445D02*
G03X53150Y195477I0J-1968D01*
G01X161418Y197445D02*
X55118D01*
G01X73426Y282874D02*
G03X69488Y286811I-3937J0D01*
G01X81300Y282874D02*
G03X69488Y294685I-11811J0D01*
G01X74016Y369685D02*
G03Y361811I0J-3937D01*
G01X53150Y551382D02*
G03X55118Y549414I1968J0D01*
G01X53150Y565162D02*
Y551382D01*
G01X55118Y549414D02*
X161418D01*
G01X55118Y567130D02*
G03X53150Y565162I0J-1968D01*
G01X161418Y567130D02*
X55118D01*
G01X73426Y652559D02*
G03X69488Y656496I-3937J0D01*
G01X81300Y652559D02*
G03X69488Y664370I-11811J0D01*
G01X55954Y731496D02*
G03X54098Y730184I0J-1969D01*
G01X153544Y731496D02*
X55954D01*
G01X80709Y43307D02*
G03X82677Y41339I1968J0D01*
G01Y47244D02*
G03X80709Y45276I0J-1968D01*
G01X188977Y47244D02*
X82677D01*
G01Y41339D02*
X188977D01*
G01X80709Y45276D02*
Y43307D01*
G01X86614Y101181D02*
G03X82677Y105118I-3937J0D01*
G01X86614Y95276D02*
Y101181D01*
G01X82677Y91339D02*
G03X86614Y95276I0J3937D01*
G01X73426Y267323D02*
G03X77363Y263386I3937J0D01*
G01X73426Y267323D02*
Y282874D01*
G01X77363Y263386D02*
X159449D01*
G01X81300Y271260D02*
Y282874D01*
G01Y271260D02*
X155512D01*
G01Y361811D02*
X74016D01*
G01X80709Y412992D02*
G03X82677Y411024I1968J0D01*
G01Y416929D02*
G03X80709Y414961I0J-1968D01*
G01X188977Y416929D02*
X82677D01*
G01Y411024D02*
X188977D01*
G01X80709Y414961D02*
Y412992D01*
G01X86614Y464961D02*
Y470866D01*
G01X82677Y461024D02*
G03X86614Y464961I0J3937D01*
G01Y470866D02*
G03X82677Y474803I-3937J0D01*
G01X73426Y637008D02*
G03X77363Y633071I3937J0D01*
G01X73426Y637008D02*
Y652559D01*
G01X77363Y633071D02*
X159449D01*
G01X81300Y640945D02*
Y652559D01*
G01Y640945D02*
X155512D01*
G01X109449Y95276D02*
Y101181D01*
G01X113386Y105118D02*
G03X109449Y101181I0J-3937D01*
G01Y95276D02*
G03X113386Y91339I3937J0D01*
G01X109449Y464961D02*
Y470866D01*
G01Y464961D02*
G03X113386Y461024I3937J0D01*
G01Y474803D02*
G03X109449Y470866I0J-3937D01*
G01X161418Y179729D02*
G03X163386Y181697I0J1968D01*
G01Y195477D02*
G03X161418Y197445I-1968J0D01*
G01X159449Y263386D02*
G03X163386Y267323I0J3937D01*
G01X155512Y303937D02*
Y271260D01*
G01X163386Y303937D02*
G03X155512I-3937J0D01*
G01Y329134D02*
G03X163386I3937J0D01*
G01X155512Y361811D02*
Y329134D01*
G01X161418Y549414D02*
G03X163386Y551382I0J1968D01*
G01Y565162D02*
G03X161418Y567130I-1968J0D01*
G01X159449Y633071D02*
G03X163386Y637008I0J3937D01*
G01X155512Y673622D02*
Y640945D01*
G01X163386Y673622D02*
G03X155512I-3937J0D01*
G01Y698819D02*
G03X163386I3937J0D01*
G01X155512Y729528D02*
Y698819D01*
G01Y729528D02*
G03X153544Y731496I-1968J0D01*
G01X163386Y181697D02*
Y195477D01*
G01Y357874D02*
Y267323D01*
G01X167323Y361811D02*
G03X163386Y357874I0J-3937D01*
G01X535433Y361811D02*
X167323D01*
G01X163386Y551382D02*
Y565162D01*
G01Y727559D02*
Y637008D01*
G01X167323Y731496D02*
G03X163386Y727559I0J-3937D01*
G01X535433Y731496D02*
X167323D01*
G01X188977Y41339D02*
G03X190945Y43307I0J1968D01*
G01Y45276D02*
G03X188977Y47244I-1968J0D01*
G01X190945Y43307D02*
Y45276D01*
G01X196851Y97244D02*
G03X194882Y95276I0J-1969D01*
G01X192914Y91339D02*
G03X194882Y93307I0J1968D01*
G01X196851Y97244D02*
X269685D01*
G01X194882Y93307D02*
Y95276D01*
G01X188977Y411024D02*
G03X190945Y412992I0J1968D01*
G01Y414961D02*
G03X188977Y416929I-1968J0D01*
G01X190945Y412992D02*
Y414961D01*
G01X196851Y466929D02*
G03X194882Y464961I-1J-1968D01*
G01X192914Y461024D02*
G03X194882Y462992I0J1968D01*
G01D02*
Y464961D01*
G01X196851Y466929D02*
X269685D01*
G01Y97244D02*
G03X273622Y101181I0J3937D01*
G01Y252756D02*
Y101181D01*
G01X261811Y105118D02*
G03X265748Y109055I0J3937D01*
G01D02*
Y260630D01*
G01X273622Y165551D02*
G03X265748I-3937J0D01*
G01Y196260D02*
G03X273622I3937J0D01*
G01X269685Y264567D02*
G03X265748Y260630I0J-3937D01*
G01X277559Y256693D02*
G03X273622Y252756I0J-3937D01*
G01X342520Y264567D02*
X269685D01*
G01X254331Y361811D02*
G03Y369685I0J3937D01*
G01X261811Y474803D02*
G03X265748Y478740I0J3937D01*
G01D02*
Y630315D01*
G01X269685Y466929D02*
G03X273622Y470866I0J3937D01*
G01Y622441D02*
Y470866D01*
G01Y535236D02*
G03X265748I-3937J0D01*
G01Y565945D02*
G03X273622I3937J0D01*
G01X277559Y626378D02*
G03X273622Y622441I0J-3937D01*
G01X269685Y634252D02*
G03X265748Y630315I0J-3937D01*
G01X342520Y634252D02*
X269685D01*
G01X561024Y256693D02*
X277559D01*
G01X285040Y369685D02*
G03Y361811I0J-3937D01*
G01X561024Y626378D02*
X277559D01*
G01X342520Y264567D02*
G03X344488Y266536I0J1968D01*
G01X342520Y634252D02*
G03X344488Y636221I0J1968D01*
G01X346457Y270473D02*
G03X344488Y268504I0J-1969D01*
G01X346457Y270473D02*
X535433D01*
G01X344488Y268504D02*
Y266536D01*
G01X350394Y320473D02*
G03X348426Y318504I0J-1968D01*
G01Y316536D02*
G03X350394Y314567I1968J-1D01*
G01D02*
X456693D01*
G01Y320473D02*
X350394D01*
G01X348426Y318504D02*
Y316536D01*
G01X346457Y640158D02*
G03X344488Y638189I0J-1969D01*
G01X346457Y640158D02*
X535433D01*
G01X344488Y638189D02*
Y636221D01*
G01X350394Y690158D02*
G03X348426Y688189I0J-1968D01*
G01Y686221D02*
G03X350394Y684252I1968J-1D01*
G01D02*
X456693D01*
G01Y690158D02*
X350394D01*
G01X348426Y688189D02*
Y686221D01*
G01X383859Y1969D02*
G03X385827Y0I1968J-1D01*
G01D02*
X523622D01*
G01X372048D02*
G03X375985Y3937I0J3937D01*
G01X383859Y1969D02*
Y32677D01*
G01X375985Y3937D02*
Y94488D01*
G01X383859Y32677D02*
G03X375985I-3937J0D01*
G01Y57874D02*
G03X383859I3937J0D01*
G01D02*
Y90551D01*
G01X379922Y98425D02*
G03X375985Y94488I0J-3937D01*
G01X458071Y90551D02*
X383859D01*
G01X462008Y98425D02*
X379922D01*
G01X375985Y166334D02*
G03X377953Y164365I1969J0D01*
G01X375985Y180113D02*
Y166334D01*
G01X377953Y164365D02*
X484252D01*
G01X377953Y182082D02*
G03X375985Y180113I0J-1968D01*
G01X484252Y182082D02*
X377953D01*
G01X383859Y369685D02*
X465355D01*
G01X372048D02*
G03X375985Y373622I0J3937D01*
G01X383859Y369685D02*
Y402362D01*
G01X375985Y373622D02*
Y464173D01*
G01X383859Y402362D02*
G03X375985I-3937J0D01*
G01Y427559D02*
G03X383859I3937J0D01*
G01D02*
Y460236D01*
G01X379922Y468110D02*
G03X375985Y464173I0J-3937D01*
G01X458071Y460236D02*
X383859D01*
G01X462008Y468110D02*
X379922D01*
G01X375985Y536019D02*
G03X377953Y534050I1969J0D01*
G01D02*
X484252D01*
G01X377953Y551767D02*
G03X375985Y549799I0J-1968D01*
G01D02*
Y536019D01*
G01X484252Y551767D02*
X377953D01*
G01X429922Y260630D02*
Y266536D01*
G01X425985Y256693D02*
G03X429922Y260630I0J3937D01*
G01Y266536D02*
G03X425985Y270473I-3937J0D01*
G01X429922Y630315D02*
Y636221D01*
G01X425985Y626378D02*
G03X429922Y630315I0J3937D01*
G01Y636221D02*
G03X425985Y640158I-3937J0D01*
G01X452756Y260630D02*
G03X456693Y256693I3937J0D01*
G01X452756Y260630D02*
Y266536D01*
G01X456693Y270473D02*
G03X452756Y266536I0J-3937D01*
G01X458662Y318504D02*
G03X456693Y320473I-1969J0D01*
G01Y314567D02*
G03X458662Y316536I0J1969D01*
G01X452756Y630315D02*
G03X456693Y626378I3937J0D01*
G01X452756Y630315D02*
Y636221D01*
G01X456693Y640158D02*
G03X452756Y636221I0J-3937D01*
G01X458662Y688189D02*
G03X456693Y690158I-1969J0D01*
G01Y684252D02*
G03X458662Y686221I0J1969D01*
G01X458071Y78937D02*
G03X469882Y67126I11811J0D01*
G01X465945Y78937D02*
G03X469882Y75000I3937J0D01*
G01X458071Y90551D02*
Y78937D01*
G01X465945Y94488D02*
Y78937D01*
G01X469882Y67126D02*
X525591D01*
G01X469882Y75000D02*
X529528D01*
G01X465945Y94488D02*
G03X462008Y98425I-3937J0D01*
G01X458662Y316536D02*
Y318504D01*
G01X465355Y361811D02*
G03Y369685I0J3937D01*
G01X458071Y448622D02*
G03X469882Y436811I11811J0D01*
G01D02*
X525591D01*
G01X465945Y448622D02*
G03X469882Y444685I3937J0D01*
G01X465945Y464173D02*
G03X462008Y468110I-3937J0D01*
G01X458071Y460236D02*
Y448622D01*
G01X465945Y464173D02*
Y448622D01*
G01X469882Y444685D02*
X529528D01*
G01X458662Y686221D02*
Y688189D01*
G01X484252Y164365D02*
G03X486221Y166334I0J1969D01*
G01D02*
Y180113D01*
G01D02*
G03X484252Y182082I-1969J0D01*
G01X496063Y369685D02*
G03Y361811I0J-3937D01*
G01Y369685D02*
X525591D01*
G01X484252Y534050D02*
G03X486221Y536019I0J1969D01*
G01Y549799D02*
G03X484252Y551767I-1969J-1D01*
G01X486221Y536019D02*
Y549799D01*
G01X523622Y0D02*
G03X525591Y1969I0J1969D01*
G01X533465Y3937D02*
G03X537402Y0I3937J0D01*
G01X525591Y1969D02*
Y20965D01*
G01X533465Y3937D02*
Y71063D01*
G01X537402Y0D02*
X561024D01*
G01X533465Y20965D02*
G03X525591I-3937J0D01*
G01Y46162D02*
G03X533465I3937J0D01*
G01X525591D02*
Y67126D01*
G01X533465Y71063D02*
G03X529528Y75000I-3937J0D01*
G01X535433Y270473D02*
G03X539370Y274410I0J3937D01*
G01D02*
Y357874D01*
G01X547244Y270473D02*
X562992D01*
G01X547244D02*
Y303543D01*
G01D02*
G03X539370I-3937J0D01*
G01Y328740D02*
G03X547244I3937J0D01*
G01D02*
Y361811D01*
G01X539370Y357874D02*
G03X535433Y361811I-3937J0D01*
G01X547244D02*
X562992D01*
G01X533465Y373622D02*
G03X537402Y369685I3937J0D01*
G01X525591D02*
Y390650D01*
G01X533465Y373622D02*
Y440748D01*
G01X537402Y369685D02*
X561024D01*
G01X533465Y390650D02*
G03X525591I-3937J0D01*
G01Y415847D02*
G03X533465I3937J0D01*
G01X525591D02*
Y436811D01*
G01X533465Y440748D02*
G03X529528Y444685I-3937J0D01*
G01X535433Y640158D02*
G03X539370Y644095I0J3937D01*
G01D02*
Y727559D01*
G01X547244Y640158D02*
X562992D01*
G01X547244D02*
Y673228D01*
G01D02*
G03X539370I-3937J0D01*
G01Y698425D02*
G03X547244I3937J0D01*
G01D02*
Y727559D01*
G01X551181Y731496D02*
G03X547244Y727559I0J-3937D01*
G01X539370D02*
G03X535433Y731496I-3937J0D01*
G01X561024Y0D02*
G03X564961Y3937I0J3937D01*
G01D02*
Y252756D01*
G01D02*
G03X561024Y256693I-3937J0D01*
G01X562992Y270473D02*
G03X564961Y272441I1J1968D01*
G01D02*
Y359843D01*
G01D02*
G03X562992Y361811I-1968J0D01*
G01X561024Y369685D02*
G03X564961Y373622I0J3937D01*
G01D02*
Y622441D01*
G01D02*
G03X561024Y626378I-3937J0D01*
G01X562992Y640158D02*
G03X564961Y642126I1J1968D01*
G01D02*
Y721654D01*
G01D02*
G03X555118Y731496I-9842J0D01*
G01X551181D02*
X555118D01*
G54D12*
G01X92955Y16952D02*
X76659Y41565D01*
G01X91974Y16151D02*
X75472Y41074D01*
G01X96395Y13512D02*
X92955Y16952D01*
G01X95135Y12990D02*
X91974Y16151D01*
G01D02*
X75472Y41074D01*
G01X92955Y16952D02*
X76659Y41565D01*
G01X95135Y12990D02*
X91974Y16151D01*
G01X96395Y13512D02*
X92955Y16952D01*
G01X80909Y53544D02*
X92547Y61247D01*
G01X79999Y54454D02*
X92055Y62434D01*
G01X76723Y47218D02*
X80909Y53544D01*
G01X75537Y47710D02*
X79999Y54454D01*
G01X76116Y44244D02*
X76723Y47218D01*
G01X74830Y44245D02*
X75537Y47710D01*
G01X76659Y41565D02*
X76116Y44244D01*
G01X75472Y41074D02*
X74830Y44245D01*
G01X79999Y54454D02*
X92055Y62434D01*
G01X80909Y53544D02*
X92547Y61247D01*
G01X75537Y47710D02*
X79999Y54454D01*
G01X76723Y47218D02*
X80909Y53544D01*
G01X74830Y44245D02*
X75537Y47710D01*
G01X76116Y44244D02*
X76723Y47218D01*
G01X75472Y41074D02*
X74830Y44245D01*
G01X76659Y41565D02*
X76116Y44244D01*
G01X92547Y61247D02*
X111031Y65007D01*
G01X92055Y62434D02*
X111031Y66293D01*
G01X92055Y62434D02*
X111031Y66293D01*
G01X92547Y61247D02*
X111031Y65007D01*
G01X96395Y11931D02*
Y13512D01*
G01X95135Y11887D02*
Y12990D01*
G01Y11887D02*
Y12990D01*
G01X96395Y11931D02*
Y13512D01*
G01X97088Y58131D02*
X110361Y60827D01*
G01X96565Y57491D02*
X97088Y58131D01*
G01X95305Y57941D02*
X96396Y59277D01*
G01X96565Y56250D02*
Y57491D01*
G01X95305Y56546D02*
Y57941D01*
G01X97088Y58131D02*
X110361Y60827D01*
G01X95305Y57941D02*
X96396Y59277D01*
G01X96565Y57491D02*
X97088Y58131D01*
G01X95305Y56546D02*
Y57941D01*
G01X96565Y56250D02*
Y57491D01*
G01X110361Y60827D02*
X123869Y58078D01*
G01X110361Y62113D02*
X123869Y59364D01*
G01X96396Y59277D02*
X110361Y62113D01*
G01D02*
X123869Y59364D01*
G01X110361Y60827D02*
X123869Y58078D01*
G01X96396Y59277D02*
X110361Y62113D01*
G01X111031Y65007D02*
X124831Y62199D01*
G01X111031Y66293D02*
X124831Y63485D01*
G01X111031Y66293D02*
X124831Y63485D01*
G01X111031Y65007D02*
X124831Y62199D01*
G01X130801Y59488D02*
X140927Y57429D01*
G01X123869Y58078D02*
X130801Y59488D01*
G01D02*
X140927Y57429D01*
G01X123869Y58078D02*
X130801Y59488D01*
G01Y60774D02*
X140927Y58715D01*
G01X123869Y59364D02*
X130801Y60774D01*
G01D02*
X140927Y58715D01*
G01X123869Y59364D02*
X130801Y60774D01*
G01X131625Y63582D02*
X140720Y61731D01*
G01X131625Y64868D02*
X140720Y63017D01*
G01X124831Y62199D02*
X131625Y63582D01*
G01X124831Y63485D02*
X131625Y64868D01*
G01D02*
X140720Y63017D01*
G01X131625Y63582D02*
X140720Y61731D01*
G01X124831Y63485D02*
X131625Y64868D01*
G01X124831Y62199D02*
X131625Y63582D01*
G01X140927Y57429D02*
X213884Y72269D01*
G01X140927Y57429D02*
X213884Y72269D01*
G01X140927Y58715D02*
X213884Y73555D01*
G01X140927Y58715D02*
X213884Y73555D01*
G01X140720Y61731D02*
X218953Y77648D01*
G01X140720Y63017D02*
X218462Y78834D01*
G01X140720Y63017D02*
X218462Y78834D01*
G01X140720Y61731D02*
X218953Y77648D01*
G01X213884Y72269D02*
X253425Y64225D01*
G01X213884Y73555D02*
X253425Y65512D01*
G01X213884Y73555D02*
X253425Y65512D01*
G01X213884Y72269D02*
X253425Y64225D01*
G01X220978Y80499D02*
X308344Y98274D01*
G01X220978Y80499D02*
X308344Y98274D01*
G01X220978Y80499D02*
X308344Y98274D01*
G01X220978Y80499D02*
X308344Y98274D01*
G01X220978Y80499D02*
X308344Y98274D01*
G01X220978Y80499D02*
X308344Y98274D01*
G01X220978Y80499D02*
X308344Y98274D01*
G01X220978Y80499D02*
X308344Y98274D01*
G01X220978Y80499D02*
X308344Y98274D01*
G01X220978Y80499D02*
X308344Y98274D01*
G01X220978Y80499D02*
X308344Y98274D01*
G01X229761Y80999D02*
X231407Y81334D01*
G01X220978Y80499D02*
X308344Y98274D01*
G01X221469Y79313D02*
X226742Y80385D01*
G01X220978Y80499D02*
X308344Y98274D01*
G01X218953Y77648D02*
X221469Y79313D01*
G01X218462Y78834D02*
X220978Y80499D01*
G01D02*
X308344Y98274D01*
G01X229761Y80999D02*
X231407Y81334D01*
G01X221469Y79313D02*
X226742Y80385D01*
G01X218462Y78834D02*
X220978Y80499D01*
G01X218953Y77648D02*
X221469Y79313D01*
G01X243753Y83846D02*
X258887Y86924D01*
G01X239089Y82897D02*
X240735Y83232D01*
G01X234425Y81948D02*
X236071Y82283D01*
G01X243753Y83846D02*
X258887Y86924D01*
G01X239089Y82897D02*
X240735Y83232D01*
G01X234425Y81948D02*
X236071Y82283D01*
G01X253425Y64225D02*
X305461Y74811D01*
G01X253425Y65511D02*
X305461Y76097D01*
G01X253425Y65511D02*
X305461Y76097D01*
G01X253425Y64225D02*
X305461Y74811D01*
G01X275897Y90385D02*
X290180Y93291D01*
G01X271233Y89436D02*
X272879Y89771D01*
G01X266569Y88487D02*
X268215Y88822D01*
G01X261905Y87538D02*
X263551Y87873D01*
G01X275897Y90385D02*
X290180Y93291D01*
G01X271233Y89436D02*
X272879Y89771D01*
G01X266569Y88487D02*
X268215Y88822D01*
G01X261905Y87538D02*
X263551Y87873D01*
G01X297862Y94854D02*
X299508Y95189D01*
G01X293198Y93905D02*
X294844Y94240D01*
G01X297862Y94854D02*
X299508Y95189D01*
G01X293198Y93905D02*
X294844Y94240D01*
G01X305461Y74811D02*
X322357Y71374D01*
G01X305461Y76097D02*
X322357Y72660D01*
G01X305461Y76097D02*
X322357Y72660D01*
G01X305461Y74811D02*
X322357Y71374D01*
G01X308835Y97088D02*
X320710Y104947D01*
G01X308344Y98274D02*
X320219Y106134D01*
G01X307190Y96752D02*
X308836Y97087D01*
G01X302526Y95803D02*
X304172Y96138D01*
G01X308344Y98274D02*
X320219Y106134D01*
G01X308835Y97088D02*
X320710Y104947D01*
G01X307190Y96752D02*
X308836Y97087D01*
G01X302526Y95803D02*
X304172Y96138D01*
G01X320710Y104947D02*
X322848Y105381D01*
G01X320219Y106134D02*
X322848Y106667D01*
G01X320219Y106134D02*
X322848Y106667D01*
G01X320710Y104947D02*
X322848Y105381D01*
G01X341026Y75170D02*
X345447Y78097D01*
G01X340534Y76357D02*
X344537Y79007D01*
G01X322357Y71374D02*
X341026Y75170D01*
G01X338888Y76022D02*
X340534Y76357D01*
G01X334224Y75073D02*
X335870Y75408D01*
G01X329559Y74124D02*
X331205Y74459D01*
G01X322357Y72660D02*
X326540Y73511D01*
G01X340534Y76357D02*
X344537Y79007D01*
G01X341026Y75170D02*
X345447Y78097D01*
G01X338888Y76022D02*
X340534Y76357D01*
G01X322357Y71374D02*
X341026Y75170D01*
G01X334224Y75073D02*
X335870Y75408D01*
G01X322357Y71374D02*
X341026Y75170D01*
G01X329559Y74124D02*
X331205Y74459D01*
G01X322357Y71374D02*
X341026Y75170D01*
G01X322357Y72660D02*
X326540Y73511D01*
G01X322357Y71374D02*
X341026Y75170D01*
G01X345271Y95058D02*
X342127D01*
G01X344891Y93798D02*
X342361D01*
G01X344891D02*
X342361D01*
G01X345271Y95058D02*
X342127D01*
G01X326774Y102567D02*
Y101775D01*
G01X328034Y102694D02*
Y101775D01*
G01X326654Y103154D02*
X326774Y102567D01*
G01X327840Y103646D02*
X328034Y102694D01*
G01X326098Y103994D02*
X326654Y103154D01*
G01X327008Y104904D02*
X327840Y103646D01*
G01X328034Y102694D02*
Y101775D01*
G01X326774Y102567D02*
Y101775D01*
G01X327840Y103646D02*
X328034Y102694D01*
G01X326654Y103154D02*
X326774Y102567D01*
G01X327008Y104904D02*
X327840Y103646D01*
G01X326098Y103994D02*
X326654Y103154D01*
G01X324512Y105044D02*
X326098Y103994D01*
G01X325003Y106231D02*
X327008Y104904D01*
G01X322848Y105381D02*
X324512Y105044D01*
G01X322848Y106667D02*
X325003Y106231D01*
G01D02*
X327008Y104904D01*
G01X324512Y105044D02*
X326098Y103994D01*
G01X322848Y106667D02*
X325003Y106231D01*
G01X322848Y105381D02*
X324512Y105044D01*
G01X345447Y78097D02*
X348496Y82703D01*
G01X344537Y79007D02*
X347309Y83195D01*
G01X344537Y79007D02*
X347309Y83195D01*
G01X345447Y78097D02*
X348496Y82703D01*
G01X348573Y92871D02*
X345271Y95058D01*
G01X347442Y92108D02*
X344891Y93798D01*
G01X349570Y87981D02*
X348573Y92871D01*
G01X348284Y87981D02*
X347442Y92108D01*
G01X348496Y82703D02*
X349570Y87981D01*
G01X347309Y83195D02*
X348284Y87981D01*
G01X347442Y92108D02*
X344891Y93798D01*
G01X348573Y92871D02*
X345271Y95058D01*
G01X348284Y87981D02*
X347442Y92108D01*
G01X349570Y87981D02*
X348573Y92871D01*
G01X347309Y83195D02*
X348284Y87981D01*
G01X348496Y82703D02*
X349570Y87981D01*
M02*
